# BASEBOARD_FAB2 (Tioga Pass) — schematic netlist excerpt (pin names and nets, part order shuffled) for the footprints in the layout excerpt that follows; sources: Cadence DE-HDL packaged netlist, KiCad conversion of Wiwynn_Tioga_Pass_MB.brd

R9E5  RES  33.2 1% CHIP  pkg 0402  page 139 : A = SPI_NIC_CS_R_N ; B = SPI_NIC_CS_N
R25W157  RES  100.0K 1% CHIP  pkg 0402  page 147 : A = PUMP_TACH0 ; B = GND
R1U5  RES  100.0K 1% CHIP  pkg 0402  page 147 : A = FAN_TACH0 ; B = GND

(kicad_pcb
	(version 20260206)
	(generator "pcbnew")
	(generator_version "10.0")
	(general
		(thickness 1.6)
		(legacy_teardrops no)
	)
	(paper "A4")
	(title_block
		(title "Wiwynn_Tioga_Pass_MB.brd")
		(comment 1 "Tioga Pass / footprints 667-669 of 4770")
	)
	(layers
		(0 "F.Cu" signal "TOP")
		(4 "In1.Cu" signal "L2GND")
		(6 "In2.Cu" signal "L3")
		(8 "In3.Cu" signal "L4GND")
		(10 "In4.Cu" signal "L5")
		(12 "In5.Cu" signal "L6GND")
		(14 "In6.Cu" signal "L7VCC")
		(16 "In7.Cu" signal "L8VCC")
		(18 "In8.Cu" signal "L9GND")
		(20 "In9.Cu" signal "L10")
		(22 "In10.Cu" signal "L11GND")
		(24 "In11.Cu" signal "L12")
		(26 "In12.Cu" signal "L13GND")
		(2 "B.Cu" signal "BOTTOM")
		(9 "F.Adhes" user "F.Adhesive")
		(11 "B.Adhes" user "B.Adhesive")
		(13 "F.Paste" user "Package Geometry/Pastemask Top")
		(15 "B.Paste" user "Package Geometry/Pastemask Bottom")
		(5 "F.SilkS" user "Ref Des/Silkscreen Top")
		(7 "B.SilkS" user "Ref Des/Silkscreen Bottom")
		(1 "F.Mask" user "Board Geometry/Soldermask Top")
		(3 "B.Mask" user "Board Geometry/Soldermask Bottom")
		(17 "Dwgs.User" user "User.Drawings")
		(19 "Cmts.User" user "User.Comments")
		(21 "Eco1.User" user "User.Eco1")
		(23 "Eco2.User" user "User.Eco2")
		(25 "Edge.Cuts" user "Board Geometry/Outline")
		(27 "Margin" user)
		(31 "F.CrtYd" user "Package Geometry/Place Bound Top")
		(29 "B.CrtYd" user "Package Geometry/Place Bound Bottom")
		(35 "F.Fab" user "Ref Des/Assembly Top")
		(33 "B.Fab" user "Ref Des/Assembly Bottom")
	)
	(footprint ""
		(layer "F.Cu")
		(at 459.3336 -30.6832)
		(property "Reference" "R1U5"
			(at 0 0 0)
			(layer "F.SilkS")
			(hide yes)
			(effects
				(font
					(size 1.27 1.27)
				)
			)
		)
		(property "Value" ""
			(at 0 0 0)
			(layer "F.Fab")
			(effects
				(font
					(size 1.27 1.27)
				)
			)
		)
		(duplicate_pad_numbers_are_jumpers no)
		(fp_poly
			(pts
				(xy -0.2794 -0.1016) (xy 0.2794 -0.1016) (xy 0.2794 0.9906) (xy -0.2794 0.9906)
			)
			(stroke
				(width 0)
				(type default)
			)
			(fill no)
			(layer "F.CrtYd")
		)
		(fp_line
			(start -0.2794 -0.1016)
			(end -0.2794 0.9906)
			(stroke
				(width 0.1)
				(type default)
			)
			(layer "F.Fab")
		)
		(fp_line
			(start -0.2794 0.9906)
			(end 0.2794 0.9906)
			(stroke
				(width 0.1)
				(type default)
			)
			(layer "F.Fab")
		)
		(fp_line
			(start 0.2794 -0.1016)
			(end -0.2794 -0.1016)
			(stroke
				(width 0.1)
				(type default)
			)
			(layer "F.Fab")
		)
		(fp_line
			(start 0.2794 0.9906)
			(end 0.2794 -0.1016)
			(stroke
				(width 0.1)
				(type default)
			)
			(layer "F.Fab")
		)
		(pad "1" smd rect
			(at 0 0)
			(size 0.508 0.508)
			(layers "F.Cu" "F.Mask" "F.Paste")
			(net "FAN_TACH0")
		)
		(pad "2" smd rect
			(at 0 0.889)
			(size 0.508 0.508)
			(layers "F.Cu" "F.Mask" "F.Paste")
			(net "GND")
		)
		(zone
			(layer "F.Cu")
			(hatch none 0.5)
			(connect_pads
				(clearance 0)
			)
			(min_thickness 0.25)
			(keepout
				(tracks allowed)
				(vias not_allowed)
				(pads allowed)
				(copperpour not_allowed)
				(footprints allowed)
			)
			(placement
				(enabled no)
				(sheetname "")
			)
			(fill
				(thermal_gap 0.5)
				(thermal_bridge_width 0.5)
				(island_removal_mode 0)
			)
			(polygon
				(pts
					(xy 459.0796 -30.4292) (xy 459.5876 -30.4292) (xy 459.5876 -30.0482) (xy 459.0796 -30.0482)
				)
			)
		)
		(zone
			(layer "F.Cu")
			(hatch none 0.5)
			(connect_pads
				(clearance 0)
			)
			(min_thickness 0.25)
			(keepout
				(tracks not_allowed)
				(vias allowed)
				(pads allowed)
				(copperpour not_allowed)
				(footprints allowed)
			)
			(placement
				(enabled no)
				(sheetname "")
			)
			(fill
				(thermal_gap 0.5)
				(thermal_bridge_width 0.5)
				(island_removal_mode 0)
			)
			(polygon
				(pts
					(xy 459.0796 -30.0482) (xy 459.5876 -30.0482) (xy 459.5876 -30.4292) (xy 459.0796 -30.4292)
				)
			)
		)
	)
	(footprint ""
		(layer "F.Cu")
		(at 490.7153 -49.8094 90)
		(property "Reference" "R9E5"
			(at 0 0 90)
			(layer "F.SilkS")
			(hide yes)
			(effects
				(font
					(size 1.27 1.27)
				)
			)
		)
		(property "Value" ""
			(at 0 0 90)
			(layer "F.Fab")
			(effects
				(font
					(size 1.27 1.27)
				)
			)
		)
		(duplicate_pad_numbers_are_jumpers no)
		(fp_poly
			(pts
				(xy -0.2794 -0.1016) (xy 0.2794 -0.1016) (xy 0.2794 0.9906) (xy -0.2794 0.9906)
			)
			(stroke
				(width 0)
				(type default)
			)
			(fill no)
			(layer "F.CrtYd")
		)
		(fp_line
			(start 0.2794 -0.1016)
			(end -0.2794 -0.1016)
			(stroke
				(width 0.1)
				(type default)
			)
			(layer "F.Fab")
		)
		(fp_line
			(start -0.2794 -0.1016)
			(end -0.2794 0.9906)
			(stroke
				(width 0.1)
				(type default)
			)
			(layer "F.Fab")
		)
		(fp_line
			(start 0.2794 0.9906)
			(end 0.2794 -0.1016)
			(stroke
				(width 0.1)
				(type default)
			)
			(layer "F.Fab")
		)
		(fp_line
			(start -0.2794 0.9906)
			(end 0.2794 0.9906)
			(stroke
				(width 0.1)
				(type default)
			)
			(layer "F.Fab")
		)
		(pad "1" smd rect
			(at 0 0 90)
			(size 0.508 0.508)
			(layers "F.Cu" "F.Mask" "F.Paste")
			(net "SPI_NIC_CS_R_N")
		)
		(pad "2" smd rect
			(at 0 0.889 90)
			(size 0.508 0.508)
			(layers "F.Cu" "F.Mask" "F.Paste")
			(net "SPI_NIC_CS_N")
		)
		(zone
			(layer "F.Cu")
			(hatch none 0.5)
			(connect_pads
				(clearance 0)
			)
			(min_thickness 0.25)
			(keepout
				(tracks allowed)
				(vias not_allowed)
				(pads allowed)
				(copperpour not_allowed)
				(footprints allowed)
			)
			(placement
				(enabled no)
				(sheetname "")
			)
			(fill
				(thermal_gap 0.5)
				(thermal_bridge_width 0.5)
				(island_removal_mode 0)
			)
			(polygon
				(pts
					(xy 490.9693 -49.5554) (xy 490.9693 -50.0634) (xy 491.3503 -50.0634) (xy 491.3503 -49.5554)
				)
			)
		)
		(zone
			(layer "F.Cu")
			(hatch none 0.5)
			(connect_pads
				(clearance 0)
			)
			(min_thickness 0.25)
			(keepout
				(tracks not_allowed)
				(vias allowed)
				(pads allowed)
				(copperpour not_allowed)
				(footprints allowed)
			)
			(placement
				(enabled no)
				(sheetname "")
			)
			(fill
				(thermal_gap 0.5)
				(thermal_bridge_width 0.5)
				(island_removal_mode 0)
			)
			(polygon
				(pts
					(xy 491.3503 -49.5554) (xy 491.3503 -50.0634) (xy 490.9693 -50.0634) (xy 490.9693 -49.5554)
				)
			)
		)
	)
	(footprint ""
		(layer "F.Cu")
		(at 431.8 -26.797)
		(property "Reference" "R25W157"
			(at -0.8382 -0.67818 0)
			(unlocked yes)
			(layer "F.SilkS")
			(effects
				(font
					(size 0.4064 0.254)
					(thickness 0.1524)
				)
				(justify left)
			)
		)
		(property "Value" ""
			(at 0 0 0)
			(layer "F.Fab")
			(effects
				(font
					(size 1.27 1.27)
				)
			)
		)
		(duplicate_pad_numbers_are_jumpers no)
		(fp_poly
			(pts
				(xy -0.2794 -0.1016) (xy 0.2794 -0.1016) (xy 0.2794 0.9906) (xy -0.2794 0.9906)
			)
			(stroke
				(width 0)
				(type default)
			)
			(fill no)
			(layer "F.CrtYd")
		)
		(fp_line
			(start -0.2794 -0.1016)
			(end -0.2794 0.9906)
			(stroke
				(width 0.1)
				(type default)
			)
			(layer "F.Fab")
		)
		(fp_line
			(start -0.2794 0.9906)
			(end 0.2794 0.9906)
			(stroke
				(width 0.1)
				(type default)
			)
			(layer "F.Fab")
		)
		(fp_line
			(start 0.2794 -0.1016)
			(end -0.2794 -0.1016)
			(stroke
				(width 0.1)
				(type default)
			)
			(layer "F.Fab")
		)
		(fp_line
			(start 0.2794 0.9906)
			(end 0.2794 -0.1016)
			(stroke
				(width 0.1)
				(type default)
			)
			(layer "F.Fab")
		)
		(pad "1" smd rect
			(at 0 0)
			(size 0.508 0.508)
			(layers "F.Cu" "F.Mask" "F.Paste")
			(net "PUMP_TACH0")
		)
		(pad "2" smd rect
			(at 0 0.889)
			(size 0.508 0.508)
			(layers "F.Cu" "F.Mask" "F.Paste")
			(net "GND")
		)
		(zone
			(layer "F.Cu")
			(hatch none 0.5)
			(connect_pads
				(clearance 0)
			)
			(min_thickness 0.25)
			(keepout
				(tracks allowed)
				(vias not_allowed)
				(pads allowed)
				(copperpour not_allowed)
				(footprints allowed)
			)
			(placement
				(enabled no)
				(sheetname "")
			)
			(fill
				(thermal_gap 0.5)
				(thermal_bridge_width 0.5)
				(island_removal_mode 0)
			)
			(polygon
				(pts
					(xy 431.546 -26.543) (xy 432.054 -26.543) (xy 432.054 -26.162) (xy 431.546 -26.162)
				)
			)
		)
		(zone
			(layer "F.Cu")
			(hatch none 0.5)
			(connect_pads
				(clearance 0)
			)
			(min_thickness 0.25)
			(keepout
				(tracks not_allowed)
				(vias allowed)
				(pads allowed)
				(copperpour not_allowed)
				(footprints allowed)
			)
			(placement
				(enabled no)
				(sheetname "")
			)
			(fill
				(thermal_gap 0.5)
				(thermal_bridge_width 0.5)
				(island_removal_mode 0)
			)
			(polygon
				(pts
					(xy 431.546 -26.162) (xy 432.054 -26.162) (xy 432.054 -26.543) (xy 431.546 -26.543)
				)
			)
		)
	)
)
